#ISCELL
  mstr_misc dns *
  *
#ISCELL
  mstr_symbols intel_corp_bpage *
  *
#ISCELL
  mstr_symbols pvddq_def *
  page219_i1
#CELL
  mstr_discrete ir354xx *
  page219_i106
#CELL
  mstr_discrete ir354xx *
  page219_i107
#CELL
  mstr_discrete res *
  page219_i108
#ISCELL
  mstr_symbols gnd *
  page219_i109
#CELL
  mstr_discrete res *
  page219_i110
#ISCELL
  mstr_symbols gnd *
  page219_i111
#ISCELL
  mstr_symbols p5v_stby *
  page219_i112
#CELL
  dev_discrete cap_a *
  page219_i113
#ISCELL
  mstr_symbols gnd *
  page219_i114
#CELL
  dev_discrete cap_a *
  page219_i116
#ISCELL
  mstr_symbols gnd *
  page219_i117
#CELL
  mstr_discrete cap *
  page219_i119
#ISCELL
  mstr_symbols gnd *
  page219_i120
#CELL
  w_hdl sc2k2p50v3kx-gp *
  page219_i121
#ISCELL
  mstr_symbols gnd *
  page219_i122
#CELL
  w_hdl 3d01r5f-gp *
  page219_i123
#CELL
  mstr_discrete cap *
  page219_i124
#ISCELL
  mstr_symbols gnd *
  page219_i125
#CELL
  w_hdl 3d01r5f-gp *
  page219_i126
#CELL
  w_hdl sc2k2p50v3kx-gp *
  page219_i127
#ISCELL
  mstr_symbols gnd *
  page219_i128
#CELL
  mstr_discrete res *
  page219_i129
#CELL
  mstr_discrete res *
  page219_i130
#ISCELL
  mstr_symbols gnd *
  page219_i19
#ISCELL
  mstr_standard offpage *
  page219_i3
#ISCELL
  mstr_standard offpage *
  page219_i33
#ISCELL
  mstr_symbols gnd *
  page219_i35
#ISCELL
  mstr_standard offpage *
  page219_i4
#CELL
  mstr_discrete cap *
  page219_i44
#CELL
  mstr_discrete cap *
  page219_i45
#CELL
  mstr_discrete cap *
  page219_i46
#CELL
  mstr_discrete cap *
  page219_i47
#CELL
  mstr_discrete cap *
  page219_i48
#CELL
  mstr_discrete cap *
  page219_i50
#CELL
  dev_discrete cap_a *
  page219_i51
#CELL
  mstr_discrete res *
  page219_i52
#CELL
  dev_discrete cap_a *
  page219_i53
#CELL
  mstr_discrete cap *
  page219_i54
#CELL
  mstr_discrete inductor *
  page219_i55
#ISCELL
  mstr_standard offpage *
  page219_i58
#ISCELL
  mstr_standard offpage *
  page219_i61
#ISCELL
  mstr_standard offpage *
  page219_i62
#ISCELL
  mstr_standard offpage *
  page219_i63
#ISCELL
  mstr_symbols pvddq_def *
  page219_i64
#CELL
  mstr_discrete inductor *
  page219_i65
#CELL
  mstr_discrete cap *
  page219_i68
#ISCELL
  mstr_symbols gnd *
  page219_i69
#ISCELL
  mstr_symbols gnd *
  page219_i7
#ISCELL
  mstr_symbols gnd *
  page219_i70
#CELL
  mstr_discrete cap *
  page219_i72
#CELL
  dev_discrete cap_a *
  page219_i73
#CELL
  mstr_discrete cap *
  page219_i75
#CELL
  mstr_discrete res *
  page219_i76
#CELL
  mstr_discrete cap *
  page219_i77
#CELL
  dev_discrete cap_a *
  page219_i78
#CELL
  mstr_discrete cap *
  page219_i79
#CELL
  mstr_discrete cap *
  page219_i80
#CELL
  mstr_discrete cap *
  page219_i81
#ISCELL
  mstr_standard offpage *
  page219_i82
#ISCELL
  mstr_symbols vcc_core *
  page219_i83
#CELL
  mstr_discrete cap *
  page219_i84
#ISCELL
  mstr_symbols gnd *
  page219_i85
#ISCELL
  mstr_symbols vcc_core *
  page219_i86
#CELL
  mstr_discrete cap *
  page219_i87
#ISCELL
  mstr_symbols p5v_stby *
  page219_i89
